# BASEBOARD_FAB2 (Tioga Pass) — schematic netlist excerpt (pin names and nets, part order shuffled) for the footprints in the layout excerpt that follows; sources: Cadence DE-HDL packaged netlist, KiCad conversion of Wiwynn_Tioga_Pass_MB.brd

C3M38  CAP_A  1.0UF 6.3V 10% X6S  pkg 0402V  page 131 : A = P1V05_PCH_STBY ; B = GND
C3U3  CAP  10UF 16V 10% X6S  pkg 0805  page 216 : A = VR_FET_SW_P12V_STBY_PVDDQ_ABC ; B = GND
R6T9  RES  100.0 1% CHIP  pkg 0402  page 112 : A = PVCCIO_CPU0 ; B = XDP_CPU_OBSFN_B1_MBP7_N

(kicad_pcb
	(version 20260206)
	(generator "pcbnew")
	(generator_version "10.0")
	(general
		(thickness 1.6)
		(legacy_teardrops no)
	)
	(paper "A4")
	(title_block
		(title "Wiwynn_Tioga_Pass_MB.brd")
		(comment 1 "Tioga Pass / footprints 3180-3182 of 4770")
	)
	(layers
		(0 "F.Cu" signal "TOP")
		(4 "In1.Cu" signal "L2GND")
		(6 "In2.Cu" signal "L3")
		(8 "In3.Cu" signal "L4GND")
		(10 "In4.Cu" signal "L5")
		(12 "In5.Cu" signal "L6GND")
		(14 "In6.Cu" signal "L7VCC")
		(16 "In7.Cu" signal "L8VCC")
		(18 "In8.Cu" signal "L9GND")
		(20 "In9.Cu" signal "L10")
		(22 "In10.Cu" signal "L11GND")
		(24 "In11.Cu" signal "L12")
		(26 "In12.Cu" signal "L13GND")
		(2 "B.Cu" signal "BOTTOM")
		(9 "F.Adhes" user "F.Adhesive")
		(11 "B.Adhes" user "B.Adhesive")
		(13 "F.Paste" user "Package Geometry/Pastemask Top")
		(15 "B.Paste" user "Package Geometry/Pastemask Bottom")
		(5 "F.SilkS" user "Ref Des/Silkscreen Top")
		(7 "B.SilkS" user "Ref Des/Silkscreen Bottom")
		(1 "F.Mask" user "Board Geometry/Soldermask Top")
		(3 "B.Mask" user "Board Geometry/Soldermask Bottom")
		(17 "Dwgs.User" user "User.Drawings")
		(19 "Cmts.User" user "User.Comments")
		(21 "Eco1.User" user "User.Eco1")
		(23 "Eco2.User" user "User.Eco2")
		(25 "Edge.Cuts" user "Board Geometry/Outline")
		(27 "Margin" user)
		(31 "F.CrtYd" user "Package Geometry/Place Bound Top")
		(29 "B.CrtYd" user "Package Geometry/Place Bound Bottom")
		(35 "F.Fab" user "Ref Des/Assembly Top")
		(33 "B.Fab" user "Ref Des/Assembly Bottom")
	)
	(footprint ""
		(layer "B.Cu")
		(at 347.5736 -5.5118 -90)
		(property "Reference" "C3U3"
			(at 0 0 90)
			(layer "B.SilkS")
			(hide yes)
			(effects
				(font
					(size 1.27 1.27)
				)
				(justify mirror)
			)
		)
		(property "Value" ""
			(at 0 0 90)
			(layer "B.Fab")
			(effects
				(font
					(size 1.27 1.27)
				)
				(justify mirror)
			)
		)
		(duplicate_pad_numbers_are_jumpers no)
		(fp_rect
			(start 0.7239 1.9939)
			(end -0.7239 -0.2159)
			(stroke
				(width 0)
				(type default)
			)
			(fill no)
			(layer "B.CrtYd")
		)
		(fp_line
			(start -0.7239 1.9939)
			(end -0.7239 -0.2159)
			(stroke
				(width 0.1)
				(type default)
			)
			(layer "B.Fab")
		)
		(fp_line
			(start 0.7239 1.9939)
			(end -0.7239 1.9939)
			(stroke
				(width 0.1)
				(type default)
			)
			(layer "B.Fab")
		)
		(fp_line
			(start -0.7239 -0.2159)
			(end 0.7239 -0.2159)
			(stroke
				(width 0.1)
				(type default)
			)
			(layer "B.Fab")
		)
		(fp_line
			(start 0.7239 -0.2159)
			(end 0.7239 1.9939)
			(stroke
				(width 0.1)
				(type default)
			)
			(layer "B.Fab")
		)
		(pad "1" smd rect
			(at 0 0 90)
			(size 1.27 1.016)
			(layers "B.Cu" "B.Mask" "B.Paste")
			(net "VR_FET_SW_P12V_STBY_PVDDQ_ABC")
		)
		(pad "2" smd rect
			(at 0 1.778 90)
			(size 1.27 1.016)
			(layers "B.Cu" "B.Mask" "B.Paste")
			(net "GND")
		)
		(zone
			(layer "B.Cu")
			(hatch none 0.5)
			(connect_pads
				(clearance 0)
			)
			(min_thickness 0.25)
			(keepout
				(tracks not_allowed)
				(vias allowed)
				(pads allowed)
				(copperpour not_allowed)
				(footprints allowed)
			)
			(placement
				(enabled no)
				(sheetname "")
			)
			(fill
				(thermal_gap 0.5)
				(thermal_bridge_width 0.5)
				(island_removal_mode 0)
			)
			(polygon
				(pts
					(xy 346.3036 -4.8768) (xy 347.0656 -4.8768) (xy 347.0656 -6.1468) (xy 346.3036 -6.1468)
				)
			)
		)
	)
	(footprint ""
		(layer "B.Cu")
		(at 179.804822 -20.014692 180)
		(property "Reference" "R6T9"
			(at 0 0 0)
			(layer "B.SilkS")
			(hide yes)
			(effects
				(font
					(size 1.27 1.27)
				)
				(justify mirror)
			)
		)
		(property "Value" ""
			(at 0 0 0)
			(layer "B.Fab")
			(effects
				(font
					(size 1.27 1.27)
				)
				(justify mirror)
			)
		)
		(duplicate_pad_numbers_are_jumpers no)
		(fp_rect
			(start 0.2794 0.9906)
			(end -0.2794 -0.1016)
			(stroke
				(width 0)
				(type default)
			)
			(fill no)
			(layer "B.CrtYd")
		)
		(fp_line
			(start 0.2794 0.9906)
			(end -0.2794 0.9906)
			(stroke
				(width 0.1)
				(type default)
			)
			(layer "B.Fab")
		)
		(fp_line
			(start 0.2794 -0.1016)
			(end 0.2794 0.9906)
			(stroke
				(width 0.1)
				(type default)
			)
			(layer "B.Fab")
		)
		(fp_line
			(start -0.2794 0.9906)
			(end -0.2794 -0.1016)
			(stroke
				(width 0.1)
				(type default)
			)
			(layer "B.Fab")
		)
		(fp_line
			(start -0.2794 -0.1016)
			(end 0.2794 -0.1016)
			(stroke
				(width 0.1)
				(type default)
			)
			(layer "B.Fab")
		)
		(pad "1" smd rect
			(at 0 0)
			(size 0.508 0.508)
			(layers "B.Cu" "B.Mask" "B.Paste")
			(net "PVCCIO_CPU0")
		)
		(pad "2" smd rect
			(at 0 0.889)
			(size 0.508 0.508)
			(layers "B.Cu" "B.Mask" "B.Paste")
			(net "XDP_CPU_OBSFN_B1_MBP7_N")
		)
		(zone
			(layer "B.Cu")
			(hatch none 0.5)
			(connect_pads
				(clearance 0)
			)
			(min_thickness 0.25)
			(keepout
				(tracks allowed)
				(vias not_allowed)
				(pads allowed)
				(copperpour not_allowed)
				(footprints allowed)
			)
			(placement
				(enabled no)
				(sheetname "")
			)
			(fill
				(thermal_gap 0.5)
				(thermal_bridge_width 0.5)
				(island_removal_mode 0)
			)
			(polygon
				(pts
					(xy 179.550822 -20.649692) (xy 179.550822 -20.268692) (xy 180.058822 -20.268692) (xy 180.058822 -20.649692)
				)
			)
		)
		(zone
			(layer "B.Cu")
			(hatch none 0.5)
			(connect_pads
				(clearance 0)
			)
			(min_thickness 0.25)
			(keepout
				(tracks not_allowed)
				(vias allowed)
				(pads allowed)
				(copperpour not_allowed)
				(footprints allowed)
			)
			(placement
				(enabled no)
				(sheetname "")
			)
			(fill
				(thermal_gap 0.5)
				(thermal_bridge_width 0.5)
				(island_removal_mode 0)
			)
			(polygon
				(pts
					(xy 179.550822 -20.649692) (xy 179.550822 -20.268692) (xy 180.058822 -20.268692) (xy 180.058822 -20.649692)
				)
			)
		)
	)
	(footprint ""
		(layer "B.Cu")
		(at 387.5786 -114.9096 90)
		(property "Reference" "C3M38"
			(at 0 0 90)
			(layer "B.SilkS")
			(hide yes)
			(effects
				(font
					(size 1.27 1.27)
				)
				(justify mirror)
			)
		)
		(property "Value" ""
			(at 0 0 90)
			(layer "B.Fab")
			(effects
				(font
					(size 1.27 1.27)
				)
				(justify mirror)
			)
		)
		(duplicate_pad_numbers_are_jumpers no)
		(fp_rect
			(start 0.2794 0.9144)
			(end -0.2794 -0.1143)
			(stroke
				(width 0)
				(type default)
			)
			(fill no)
			(layer "B.CrtYd")
		)
		(fp_line
			(start 0.2794 -0.1143)
			(end -0.2794 -0.1143)
			(stroke
				(width 0.1)
				(type default)
			)
			(layer "B.Fab")
		)
		(fp_line
			(start -0.2794 -0.1143)
			(end -0.2794 0.9144)
			(stroke
				(width 0.1)
				(type default)
			)
			(layer "B.Fab")
		)
		(fp_line
			(start 0.2794 0.9144)
			(end 0.2794 -0.1143)
			(stroke
				(width 0.1)
				(type default)
			)
			(layer "B.Fab")
		)
		(fp_line
			(start -0.2794 0.9144)
			(end 0.2794 0.9144)
			(stroke
				(width 0.1)
				(type default)
			)
			(layer "B.Fab")
		)
		(pad "1" smd custom
			(at 0 0)
			(size 0.10414 0.10414)
			(layers "B.Cu" "B.Mask" "B.Paste")
			(net "P1V05_PCH_STBY")
			(options
				(clearance outline)
				(anchor circle)
			)
			(primitives
				(gr_poly
					(pts
						(xy -0.20828 -0.08636) (xy -0.20828 0.08636) (xy -0.08636 0.20828) (xy 0.086614 0.20828) (xy 0.20828 0.086614)
						(xy 0.20828 -0.08636) (xy 0.08636 -0.20828) (xy -0.08636 -0.20828)
					)
					(width 0)
					(fill yes)
				)
			)
		)
		(pad "2" smd custom
			(at 0 0.8001)
			(size 0.10414 0.10414)
			(layers "B.Cu" "B.Mask" "B.Paste")
			(net "GND")
			(options
				(clearance outline)
				(anchor circle)
			)
			(primitives
				(gr_poly
					(pts
						(xy -0.20828 -0.08636) (xy -0.20828 0.08636) (xy -0.08636 0.20828) (xy 0.086614 0.20828) (xy 0.20828 0.086614)
						(xy 0.20828 -0.08636) (xy 0.08636 -0.20828) (xy -0.08636 -0.20828)
					)
					(width 0)
					(fill yes)
				)
			)
		)
		(zone
			(layer "B.Cu")
			(hatch none 0.5)
			(connect_pads
				(clearance 0)
			)
			(min_thickness 0.25)
			(keepout
				(tracks not_allowed)
				(vias allowed)
				(pads allowed)
				(copperpour not_allowed)
				(footprints allowed)
			)
			(placement
				(enabled no)
				(sheetname "")
			)
			(fill
				(thermal_gap 0.5)
				(thermal_bridge_width 0.5)
				(island_removal_mode 0)
			)
			(polygon
				(pts
					(xy 387.78815 -114.99723) (xy 388.16915 -114.99723) (xy 388.16915 -114.82197) (xy 387.78815 -114.821716)
				)
			)
		)
		(zone
			(layer "B.Cu")
			(hatch none 0.5)
			(connect_pads
				(clearance 0)
			)
			(min_thickness 0.25)
			(keepout
				(tracks allowed)
				(vias not_allowed)
				(pads allowed)
				(copperpour not_allowed)
				(footprints allowed)
			)
			(placement
				(enabled no)
				(sheetname "")
			)
			(fill
				(thermal_gap 0.5)
				(thermal_bridge_width 0.5)
				(island_removal_mode 0)
			)
			(polygon
				(pts
					(xy 387.78815 -114.99723) (xy 388.16915 -114.99723) (xy 388.16915 -114.82197) (xy 387.78815 -114.821716)
				)
			)
		)
	)
)
